# T6G (Grand Teton) — schematic netlist excerpt (pin names and nets, part order shuffled) for the footprints in the layout excerpt that follows; sources: Cadence DE-HDL packaged netlist, KiCad conversion of 04192023_DAF0TMB3IC0_F0TG_MB_C_brd_V02_OCP.brd

PR3926  Q_RES  75K 0.1% CHIP  pkg 0402LF  page 262 : A = P12V_PSU ; B = HSC_VSENSE

U9050  74LVC1G08W57  74LVC1G08W5-7 IC  pkg SOT25-5_0-95_3X1-6  page 136
  A  = OCP_V3_1_P3V3_PWRGD
  B  = HP_LVC3_OCP_V3_1_P12V_R2_PWRGD
  GND  = GND
  Y  = HP_LVC3_OCP_V3_1_PWRGD_R2
  VCC  = P3V3_AUX

(kicad_pcb
	(version 20260206)
	(generator "pcbnew")
	(generator_version "10.0")
	(general
		(thickness 1.6)
		(legacy_teardrops no)
	)
	(paper "A4")
	(title_block
		(title "04192023_DAF0TMB3IC0_F0TG_MB_C_brd_V02_OCP.brd")
		(comment 1 "Grand Teton / footprints 1931-1932 of 8354")
	)
	(layers
		(0 "F.Cu" signal "TOP")
		(4 "In1.Cu" signal "GND")
		(6 "In2.Cu" signal "IN1")
		(8 "In3.Cu" signal "GND1")
		(10 "In4.Cu" signal "IN2")
		(12 "In5.Cu" signal "GND2")
		(14 "In6.Cu" signal "IN3")
		(16 "In7.Cu" signal "GND3")
		(18 "In8.Cu" signal "VCC")
		(20 "In9.Cu" signal "VCC1")
		(22 "In10.Cu" signal "GND4")
		(24 "In11.Cu" signal "IN4")
		(26 "In12.Cu" signal "GND5")
		(28 "In13.Cu" signal "IN5")
		(30 "In14.Cu" signal "GND6")
		(32 "In15.Cu" signal "IN6")
		(34 "In16.Cu" signal "GND7")
		(2 "B.Cu" signal "BOTTOM")
		(9 "F.Adhes" user "F.Adhesive")
		(11 "B.Adhes" user "B.Adhesive")
		(13 "F.Paste" user "Package Geometry/Pastemask Top")
		(15 "B.Paste" user "Package Geometry/Pastemask Bottom")
		(5 "F.SilkS" user "Ref Des/Silkscreen Top")
		(7 "B.SilkS" user "Ref Des/Silkscreen Bottom")
		(1 "F.Mask" user "Board Geometry/Soldermask Top")
		(3 "B.Mask" user "Board Geometry/Soldermask Bottom")
		(17 "Dwgs.User" user "User.Drawings")
		(19 "Cmts.User" user "User.Comments")
		(21 "Eco1.User" user "User.Eco1")
		(23 "Eco2.User" user "User.Eco2")
		(25 "Edge.Cuts" user "Board Geometry/Outline")
		(27 "Margin" user)
		(31 "F.CrtYd" user "Package Geometry/Place Bound Top")
		(29 "B.CrtYd" user "Package Geometry/Place Bound Bottom")
		(35 "F.Fab" user "Ref Des/Assembly Top")
		(33 "B.Fab" user "Ref Des/Assembly Bottom")
	)
	(footprint ""
		(layer "F.Cu")
		(at 184.5945 -408.110182 180)
		(property "Reference" "PR3926"
			(at 0 0 180)
			(layer "F.SilkS")
			(hide yes)
			(effects
				(font
					(size 1.27 1.27)
				)
			)
		)
		(property "Value" ""
			(at 0 0 180)
			(layer "F.Fab")
			(effects
				(font
					(size 1.27 1.27)
				)
			)
		)
		(duplicate_pad_numbers_are_jumpers no)
		(fp_line
			(start 0.7874 0.4064)
			(end -0.7874 0.4064)
			(stroke
				(width 0.1524)
				(type default)
			)
			(layer "F.SilkS")
		)
		(fp_line
			(start 0.7874 -0.4064)
			(end 0.7874 0.4064)
			(stroke
				(width 0.1524)
				(type default)
			)
			(layer "F.SilkS")
		)
		(fp_line
			(start -0.7874 0.4064)
			(end -0.7874 -0.4064)
			(stroke
				(width 0.1524)
				(type default)
			)
			(layer "F.SilkS")
		)
		(fp_line
			(start -0.7874 -0.4064)
			(end 0.7874 -0.4064)
			(stroke
				(width 0.1524)
				(type default)
			)
			(layer "F.SilkS")
		)
		(fp_line
			(start 0.67945 0.3048)
			(end 0.120396 0.3048)
			(stroke
				(width 0.1)
				(type default)
			)
			(layer "F.Fab")
		)
		(fp_line
			(start 0.67945 -0.3048)
			(end 0.67945 0.3048)
			(stroke
				(width 0.1)
				(type default)
			)
			(layer "F.Fab")
		)
		(fp_line
			(start 0.12065 -0.2794)
			(end 0.12065 -0.3048)
			(stroke
				(width 0.1)
				(type default)
			)
			(layer "F.Fab")
		)
		(fp_line
			(start 0.12065 -0.3048)
			(end 0.67945 -0.3048)
			(stroke
				(width 0.1)
				(type default)
			)
			(layer "F.Fab")
		)
		(fp_line
			(start 0.120396 0.3048)
			(end 0.120396 0.2794)
			(stroke
				(width 0.1)
				(type default)
			)
			(layer "F.Fab")
		)
		(fp_line
			(start 0.120396 0.2794)
			(end -0.12065 0.2794)
			(stroke
				(width 0.1)
				(type default)
			)
			(layer "F.Fab")
		)
		(fp_line
			(start -0.12065 0.3048)
			(end -0.67945 0.3048)
			(stroke
				(width 0.1)
				(type default)
			)
			(layer "F.Fab")
		)
		(fp_line
			(start -0.12065 0.2794)
			(end -0.12065 0.3048)
			(stroke
				(width 0.1)
				(type default)
			)
			(layer "F.Fab")
		)
		(fp_line
			(start -0.12065 -0.2794)
			(end 0.12065 -0.2794)
			(stroke
				(width 0.1)
				(type default)
			)
			(layer "F.Fab")
		)
		(fp_line
			(start -0.12065 -0.305054)
			(end -0.12065 -0.2794)
			(stroke
				(width 0.1)
				(type default)
			)
			(layer "F.Fab")
		)
		(fp_line
			(start -0.67945 0.3048)
			(end -0.67945 -0.305054)
			(stroke
				(width 0.1)
				(type default)
			)
			(layer "F.Fab")
		)
		(fp_line
			(start -0.67945 -0.305054)
			(end -0.12065 -0.305054)
			(stroke
				(width 0.1)
				(type default)
			)
			(layer "F.Fab")
		)
		(pad "1" smd circle
			(at -0.40005 0 180)
			(size 0 0)
			(layers "F.Cu" "F.Mask" "F.Paste")
			(net "P12V_PSU")
		)
		(pad "2" smd circle
			(at 0.40005 0 180)
			(size 0 0)
			(layers "F.Cu" "F.Mask" "F.Paste")
			(net "HSC_VSENSE")
		)
	)
	(footprint ""
		(layer "F.Cu")
		(at 219.99956 -103.17226 180)
		(property "Reference" "U9050"
			(at -3.35915 -1.37668 90)
			(unlocked yes)
			(layer "F.SilkS")
			(effects
				(font
					(size 0.7874 0.5842)
					(thickness 0.1524)
				)
				(justify left)
			)
		)
		(property "Value" ""
			(at 0 0 180)
			(layer "F.Fab")
			(effects
				(font
					(size 1.27 1.27)
				)
			)
		)
		(duplicate_pad_numbers_are_jumpers no)
		(fp_line
			(start 1.733296 1.549908)
			(end 1.733296 -1.549908)
			(stroke
				(width 0.1524)
				(type default)
			)
			(layer "F.SilkS")
		)
		(fp_line
			(start 1.733296 -1.549908)
			(end 0.660908 -1.549908)
			(stroke
				(width 0.1524)
				(type default)
			)
			(layer "F.SilkS")
		)
		(fp_line
			(start 0.660908 -1.549908)
			(end 0 -0.889)
			(stroke
				(width 0.1524)
				(type default)
			)
			(layer "F.SilkS")
		)
		(fp_line
			(start 0 -0.889)
			(end -0.660908 -1.549908)
			(stroke
				(width 0.1524)
				(type default)
			)
			(layer "F.SilkS")
		)
		(fp_line
			(start -0.660908 -1.549908)
			(end -1.733296 -1.549908)
			(stroke
				(width 0.1524)
				(type default)
			)
			(layer "F.SilkS")
		)
		(fp_line
			(start -1.733296 1.549908)
			(end 1.733296 1.549908)
			(stroke
				(width 0.1524)
				(type default)
			)
			(layer "F.SilkS")
		)
		(fp_line
			(start -1.733296 -1.549908)
			(end -1.733296 1.549908)
			(stroke
				(width 0.1524)
				(type default)
			)
			(layer "F.SilkS")
		)
		(fp_poly
			(pts
				(xy -2.4384 -1.20396) (xy -2.4384 -0.69596) (xy -1.9304 -0.94996)
			)
			(stroke
				(width 0)
				(type default)
			)
			(fill yes)
			(layer "F.SilkS")
		)
		(fp_line
			(start 0.849884 1.549908)
			(end 0.849884 -1.549908)
			(stroke
				(width 0.1)
				(type default)
			)
			(layer "F.Fab")
		)
		(fp_line
			(start 0.849884 -1.549908)
			(end -0.849884 -1.549908)
			(stroke
				(width 0.1)
				(type default)
			)
			(layer "F.Fab")
		)
		(fp_line
			(start -0.849884 1.549908)
			(end 0.849884 1.549908)
			(stroke
				(width 0.1)
				(type default)
			)
			(layer "F.Fab")
		)
		(fp_line
			(start -0.849884 -1.549908)
			(end -0.849884 1.549908)
			(stroke
				(width 0.1)
				(type default)
			)
			(layer "F.Fab")
		)
		(fp_poly
			(pts
				(xy -2.4384 -1.20396) (xy -2.4384 -0.69596) (xy -1.9304 -0.94996)
			)
			(stroke
				(width 0)
				(type default)
			)
			(fill yes)
			(layer "F.Fab")
		)
		(pad "1" smd rect
			(at -1.199896 -0.94996 90)
			(size 0.5588 0.8128)
			(layers "F.Cu" "F.Mask" "F.Paste")
			(net "OCP_V3_1_P3V3_PWRGD")
		)
		(pad "2" smd rect
			(at -1.199896 0 90)
			(size 0.5588 0.8128)
			(layers "F.Cu" "F.Mask" "F.Paste")
			(net "HP_LVC3_OCP_V3_1_P12V_R2_PWRGD")
		)
		(pad "3" smd rect
			(at -1.199896 0.94996 90)
			(size 0.5588 0.8128)
			(layers "F.Cu" "F.Mask" "F.Paste")
			(net "GND")
		)
		(pad "4" smd rect
			(at 1.199896 0.94996 90)
			(size 0.5588 0.8128)
			(layers "F.Cu" "F.Mask" "F.Paste")
			(net "HP_LVC3_OCP_V3_1_PWRGD_R2")
		)
		(pad "5" smd rect
			(at 1.199896 -0.94996 90)
			(size 0.5588 0.8128)
			(layers "F.Cu" "F.Mask" "F.Paste")
			(net "P3V3_AUX")
		)
	)
)
